M48
INCH,TZ
T01C.012
T02C.016
T03C.029
T04C.086
T05C.093
;LEADER: 12 
;HEADER: 
;CODE  : ASCII 
;FILE  : 13919-sa-1-4.drl for board 13919-sa.brd ... layers TOP and BOTTOM
;T01 Holesize 1. = 12.000000 Tolerance = +0.000000/-0.000000 PLATED MILS Quantity = 37
;T02 Holesize 2. = 16.000000 Tolerance = +0.000000/-0.000000 PLATED MILS Quantity = 17
;T03 Holesize 3. = 29.000000 Tolerance = +0.000000/-0.000000 PLATED MILS Quantity = 164
;T04 Holesize 4. = 86.000000 Tolerance = +0.000000/-0.000000 NON_PLATED MILS Quantity = 6
;T05 Holesize 5. = 93.000000 Tolerance = +0.000000/-0.000000 NON_PLATED MILS Quantity = 2
%
G90
T01
X35363Y37960
X38133Y31500
X45633Y31600
X52733Y31400
X60633Y31500
X68633Y31400
X77233Y31700
X84233Y31400
X92533Y31500
X100733
X108333Y31600
X116233Y31500
X124233Y31600
X132333
X139733Y31500
X147833
X155433Y31600
X163733Y31500
X171333Y31600
X179133
X188976Y31543
X194933Y31600
X202433Y31400
X210633Y31500
X219033Y31600
X226933Y31500
X234333Y31400
X242333Y31600
X249533Y31400
X258233Y31300
X266033Y31020
X274433Y31400
X280933
X288533Y31020
X295275Y31658
X329633Y31100
X338583Y32050
T02
X17033Y53450
X15333Y62700
X15633Y69500
X21533Y59100
X30833Y58700
X25733Y53450
X30680Y42700
X23720Y37880
X347544Y32400
X343019Y32504
X344360Y43670
X340080Y47960
X343700Y53890
X340010Y58570
X357350Y72160
X355770Y78680
X354650Y89890
T03
X23623Y65551
X31498
X39373
X47243
X55118
X62993
X70868
X78743
X86613
X94488
X102363
X110238
X118113
X125983
X133858
X141733
X149608
X157483
X165353
X173228
X181103
X188978
X196853
X204723
X212598
X220473
X228348
X236223
X244093
X251968
X259843
X267718
X275593
X283463
X291338
X299213
X314963
X322833
X330708
X338583
X346458
X350393Y73426
X342518
X334648
X326773
X318898
X311023
X295278
X287403
X279528
X271653
X263778
X255908
X248033
X240158
X232283
X224408
X216538
X208663
X200788
X192913
X185038
X177168
X169293
X161418
X153543
X145668
X137798
X129923
X122048
X114173
X106298
X98428
X90553
X82678
X74803
X66928
X59058
X51183
X43308
X35433
X27558
Y83266
X35433
X43308
X51183
X59058
X66928
X74803
X82678
X90553
X98428
X106298
X114173
X122048
X129923
X137798
X145668
X153543
X161418
X169293
X177168
X185038
X192913
X200788
X208663
X216538
X224408
X232283
X240158
X248033
X255908
X263778
X271653
X279528
X287403
X295278
X311023
X318898
X326773
X334648
X342518
X350393
X346458Y91141
X338583
X330708
X322833
X314963
X299213
X291338
X283463
X275593
X267718
X259843
X251968
X244093
X236223
X228348
X220473
X212598
X204723
X196853
X188978
X181103
X173228
X165353
X157483
X149608
X141733
X133858
X125983
X118113
X110238
X102363
X94488
X86613
X78743
X70868
X62993
X55118
X47243
X39373
X31498
X23623
T04
X-2462Y651994
X8950Y97440
X8750Y50860
X364570Y96910
X758452Y17317
X755722Y677788
T05
X16538Y78346
X304528
M30
